# T6G (Grand Teton) — schematic netlist excerpt (pin names and nets, part order shuffled) for the footprints in the layout excerpt that follows; sources: Cadence DE-HDL packaged netlist, KiCad conversion of 04192023_DAF0TMB3IC0_F0TG_MB_C_brd_V02_OCP.brd

J32  SCONN288_DDR506112002KQ  IO  pkg DDR288S_1-1VXC  page 102
  VIN_BULK0  = P12V_MEM_CPU1
  RFU0  = NC
  VIN_MGMT  = P3V3_AUX
  HSCL  = I3C_SPD_DDRE_CPU1_SCL
  HSDA  = I3C_SPD_DDRE_CPU1_SDA
  VSS0  = GND
  DQ0_A  = M_E_CPU1_SA_DQ<0>
  VSS1  = GND
  DQ1_A  = M_E_CPU1_SA_DQ<1>
  VSS2  = GND
  DQS0_A_T  = M_E_CPU1_SA_DQS_DP<0>
  DQS0_A_C  = M_E_CPU1_SA_DQS_DN<0>
  VSS3  = GND
  DQ4_A  = M_E_CPU1_SA_DQ<4>
  VSS4  = GND
  DQ5_A  = M_E_CPU1_SA_DQ<5>
  VSS5  = GND
  DQ8_A  = M_E_CPU1_SA_DQ<8>
  VSS6  = GND
  DQ9_A  = M_E_CPU1_SA_DQ<9>
  VSS7  = GND
  DQS1_A_T  = M_E_CPU1_SA_DQS_DP<1>
  DQS1_A_C  = M_E_CPU1_SA_DQS_DN<1>
  VSS8  = GND
  DQ12_A  = M_E_CPU1_SA_DQ<12>
  VSS9  = GND
  DQ13_A  = M_E_CPU1_SA_DQ<13>
  VSS10  = GND
  DQ16_A  = M_E_CPU1_SA_DQ<16>
  VSS11  = GND
  DQ17_A  = M_E_CPU1_SA_DQ<17>
  VSS12  = GND
  DQS2_A_T  = M_E_CPU1_SA_DQS_DP<2>
  DQS2_A_C  = M_E_CPU1_SA_DQS_DN<2>
  VSS13  = GND
  DQ20_A  = M_E_CPU1_SA_DQ<20>
  VSS14  = GND
  DQ21_A  = M_E_CPU1_SA_DQ<21>
  VSS15  = GND
  DQ24_A  = M_E_CPU1_SA_DQ<24>
  VSS16  = GND
  DQ25_A  = M_E_CPU1_SA_DQ<25>
  VSS17  = GND
  DQS3_A_T  = M_E_CPU1_SA_DQS_DP<3>
  DQS3_A_C  = M_E_CPU1_SA_DQS_DN<3>
  VSS18  = GND
  DQ28_A  = M_E_CPU1_SA_DQ<28>
  VSS19  = GND
  DQ29_A  = M_E_CPU1_SA_DQ<29>
  VSS20  = GND
  CB0_A  = M_E_CPU1_SA_CB<0>
  VSS21  = GND
  CB1_A  = M_E_CPU1_SA_CB<1>
  VSS22  = GND
  DQS4_A_T  = M_E_CPU1_SA_DQS_DP<4>
  DQS4_A_C  = M_E_CPU1_SA_DQS_DN<4>
  VSS23  = GND
  CB4_A  = M_E_CPU1_SA_CB<4>
  VSS24  = GND
  CB5_A  = M_E_CPU1_SA_CB<5>
  VSS25  = GND
  ALERT_N  = M_E_CPU1_ALERT_N
  VSS26  = GND
  CS0_A_N  = M_E_CPU1_SA_CS_N<0>
  VSS27  = GND
  CA0_A  = M_E_CPU1_SA_CA<0>
  VSS28  = GND
  CA2_A  = M_E_CPU1_SA_CA<2>
  VSS29  = GND
  CA4_A  = M_E_CPU1_SA_CA<4>
  VSS30  = GND
  CA6_A  = M_E_CPU1_SA_CA<6>
  VSS31  = GND
  PAR_A  = M_E_CPU1_SA_PAR
  VSS32  = GND
  CA0_B  = M_E_CPU1_SB_CA<0>
  VSS33  = GND
  CA2_B  = M_E_CPU1_SB_CA<2>
  VSS34  = GND
  CA4_B  = M_E_CPU1_SB_CA<4>
  VSS35  = GND
  CA6_B  = M_E_CPU1_SB_CA<6>
  VSS36  = GND
  CS0_B_N  = M_E_CPU1_SB_CS_N<0>
  VSS37  = GND
  \lbd||rsp_a_n\  = M_E_CPU1_SA_RSP<0>
  \lbs||rsp_b_n\  = M_E_CPU1_SB_RSP<0>
  VSS38  = GND
  CB4_B  = M_E_CPU1_SB_CB<4>
  VSS39  = GND
  CB5_B  = M_E_CPU1_SB_CB<5>
  VSS40  = GND
  \dqs9_b_t||tdqs9_b_t||dbi4_b_n\  = M_E_CPU1_SB_DQS_DP<9>
  \dqs9_b_c||tdqs9_b_c\  = M_E_CPU1_SB_DQS_DN<9>
  VSS41  = GND
  CB0_B  = M_E_CPU1_SB_CB<0>
  VSS42  = GND
  CB1_B  = M_E_CPU1_SB_CB<1>
  VSS43  = GND
  DQ0_B  = M_E_CPU1_SB_DQ<0>
  VSS44  = GND
  DQ1_B  = M_E_CPU1_SB_DQ<1>
  VSS45  = GND
  DQS0_B_T  = M_E_CPU1_SB_DQS_DP<0>
  DQS0_B_C  = M_E_CPU1_SB_DQS_DN<0>
  VSS46  = GND
  DQ4_B  = M_E_CPU1_SB_DQ<4>
  VSS47  = GND
  DQ5_B  = M_E_CPU1_SB_DQ<5>
  VSS48  = GND
  DQ8_B  = M_E_CPU1_SB_DQ<8>
  VSS49  = GND
  DQ9_B  = M_E_CPU1_SB_DQ<9>
  VSS50  = GND
  DQS1_B_T  = M_E_CPU1_SB_DQS_DP<1>
  DQS1_B_C  = M_E_CPU1_SB_DQS_DN<1>
  VSS51  = GND
  DQ12_B  = M_E_CPU1_SB_DQ<12>
  VSS52  = GND
  DQ13_B  = M_E_CPU1_SB_DQ<13>
  VSS53  = GND
  DQ16_B  = M_E_CPU1_SB_DQ<16>
  VSS54  = GND
  DQ17_B  = M_E_CPU1_SB_DQ<17>
  VSS55  = GND
  DQS2_B_T  = M_E_CPU1_SB_DQS_DP<2>
  DQS2_B_C  = M_E_CPU1_SB_DQS_DN<2>
  VSS56  = GND
  DQ20_B  = M_E_CPU1_SB_DQ<20>
  VSS57  = GND
  DQ21_B  = M_E_CPU1_SB_DQ<21>
  VSS58  = GND
  DQ24_B  = M_E_CPU1_SB_DQ<24>
  VSS59  = GND
  DQ25_B  = M_E_CPU1_SB_DQ<25>
  VSS60  = GND
  DQS3_B_T  = M_E_CPU1_SB_DQS_DP<3>
  DQS3_B_C  = M_E_CPU1_SB_DQS_DN<3>
  VSS61  = GND
  DQ28_B  = M_E_CPU1_SB_DQ<28>
  VSS62  = GND
  DQ29_B  = M_E_CPU1_SB_DQ<29>
  VSS63  = GND
  RFU1  = NC
  VIN_BULK1  = P12V_MEM_CPU1
  VIN_BULK2  = P12V_MEM_CPU1
  \pwr_good||fail_n\  = PWRGD_CHE_CPU1_DIMM
  HAS  = PD_CHE_CPU1_DIMM_SAA
  RFU2  = NC
  RFU3  = NC
  VSS64  = GND
  DQ2_A  = M_E_CPU1_SA_DQ<2>
  VSS65  = GND
  DQ3_A  = M_E_CPU1_SA_DQ<3>
  VSS66  = GND
  \dqs5_a_c||tdqs5_a_c||dqs5_a_t||tdqs5_a_t\  = M_E_CPU1_SA_DQS_DN<5>
  \dqs5_a_t||tdqs5_a_t\  = M_E_CPU1_SA_DQS_DP<5>
  VSS67  = GND
  DQ6_A  = M_E_CPU1_SA_DQ<6>
  VSS68  = GND
  DQ7_A  = M_E_CPU1_SA_DQ<7>
  VSS69  = GND
  DQ10_A  = M_E_CPU1_SA_DQ<10>
  VSS70  = GND
  DQ11_A  = M_E_CPU1_SA_DQ<11>
  VSS71  = GND
  \dqs6_a_c||tdqs6_a_c||dqs6_a_t||tdqs6_a_t\  = M_E_CPU1_SA_DQS_DN<6>
  \dqs6_a_t||tdqs6_a_t\  = M_E_CPU1_SA_DQS_DP<6>
  VSS72  = GND
  DQ14_A  = M_E_CPU1_SA_DQ<14>
  VSS73  = GND
  DQ15_A  = M_E_CPU1_SA_DQ<15>
  VSS74  = GND
  DQ18_A  = M_E_CPU1_SA_DQ<18>
  VSS75  = GND
  DQ19_A  = M_E_CPU1_SA_DQ<19>
  VSS76  = GND
  \dqs7_a_c||tdqs7_a_c\  = M_E_CPU1_SA_DQS_DN<7>
  \dqs7_a_t||tdqs7_a_t\  = M_E_CPU1_SA_DQS_DP<7>
  VSS77  = GND
  DQ22_A  = M_E_CPU1_SA_DQ<22>
  VSS78  = GND
  DQ23_A  = M_E_CPU1_SA_DQ<23>
  VSS79  = GND
  DQ26_A  = M_E_CPU1_SA_DQ<26>
  VSS80  = GND
  DQ27_A  = M_E_CPU1_SA_DQ<27>
  VSS81  = GND
  \dqs8_a_c||tdqs8_a_c\  = M_E_CPU1_SA_DQS_DN<8>
  \dqs8_a_t||tdqs8_a_t\  = M_E_CPU1_SA_DQS_DP<8>
  VSS82  = GND
  DQ30_A  = M_E_CPU1_SA_DQ<30>
  VSS83  = GND
  DQ31_A  = M_E_CPU1_SA_DQ<31>
  VSS84  = GND
  CB2_A  = M_E_CPU1_SA_CB<2>
  VSS85  = GND
  CB3_A  = M_E_CPU1_SA_CB<3>
  VSS86  = GND
  \dqs9_a_c||tdqs9_a_c\  = M_E_CPU1_SA_DQS_DN<9>
  \dqs9_a_t||tdqs9_a_t\  = M_E_CPU1_SA_DQS_DP<9>
  VSS87  = GND
  CB6_A  = M_E_CPU1_SA_CB<6>
  VSS88  = GND
  CB7_A  = M_E_CPU1_SA_CB<7>
  VSS89  = GND
  RESET_N  = M_E_CPU1_RESET_N
  VSS90  = GND
  CS1_A_N  = M_E_CPU1_SA_CS_N<1>
  VSS91  = GND
  CA1_A  = M_E_CPU1_SA_CA<1>
  VSS92  = GND
  CA3_A  = M_E_CPU1_SA_CA<3>
  VSS93  = GND
  CA5_A  = M_E_CPU1_SA_CA<5>
  VSS94  = GND
  CK_T  = M_E_CPU1_CLK_DP<0>
  CK_C  = M_E_CPU1_CLK_DN<0>
  VSS95  = GND
  RFU4  = NC
  CA1_B  = M_E_CPU1_SB_CA<1>
  VSS96  = GND
  CA3_B  = M_E_CPU1_SB_CA<3>
  VSS97  = GND
  CA5_B  = M_E_CPU1_SB_CA<5>
  VSS98  = GND
  PAR_B  = M_E_CPU1_SB_PAR
  VSS99  = GND
  CS1_B_N  = M_E_CPU1_SB_CS_N<1>
  VSS100  = GND
  RFU5  = NC
  RFU6  = NC
  VSS101  = GND
  CB6_B  = M_E_CPU1_SB_CB<6>
  VSS102  = GND
  CB7_B  = M_E_CPU1_SB_CB<7>
  VSS103  = GND
  DQS4_B_C  = M_E_CPU1_SB_DQS_DN<4>
  DQS4_B_T  = M_E_CPU1_SB_DQS_DP<4>
  VSS104  = GND
  CB2_B  = M_E_CPU1_SB_CB<2>
  VSS105  = GND
  CB3_B  = M_E_CPU1_SB_CB<3>
  VSS106  = GND
  DQ2_B  = M_E_CPU1_SB_DQ<2>
  VSS107  = GND
  DQ3_B  = M_E_CPU1_SB_DQ<3>
  VSS108  = GND
  \dqs5_b_c||tdqs5_b_c\  = M_E_CPU1_SB_DQS_DN<5>
  \dqs5_b_t||tdqs5_b_t\  = M_E_CPU1_SB_DQS_DP<5>
  VSS109  = GND
  DQ6_B  = M_E_CPU1_SB_DQ<6>
  VSS110  = GND
  DQ7_B  = M_E_CPU1_SB_DQ<7>
  VSS111  = GND
  DQ10_B  = M_E_CPU1_SB_DQ<10>
  VSS112  = GND
  DQ11_B  = M_E_CPU1_SB_DQ<11>
  VSS113  = GND
  \dqs6_b_c||tdqs6_b_c\  = M_E_CPU1_SB_DQS_DN<6>
  \dqs6_b_t||tdqs6_b_t\  = M_E_CPU1_SB_DQS_DP<6>
  VSS114  = GND
  DQ14_B  = M_E_CPU1_SB_DQ<14>
  VSS115  = GND
  DQ15_B  = M_E_CPU1_SB_DQ<15>
  VSS116  = GND
  DQ18_B  = M_E_CPU1_SB_DQ<18>
  VSS117  = GND
  DQ19_B  = M_E_CPU1_SB_DQ<19>
  VSS118  = GND
  \dqs7_b_c||tdqs7_b_c\  = M_E_CPU1_SB_DQS_DN<7>
  \dqs7_b_t||tdqs7_b_t\  = M_E_CPU1_SB_DQS_DP<7>
  VSS119  = GND
  DQ22_B  = M_E_CPU1_SB_DQ<22>
  VSS120  = GND
  DQ23_B  = M_E_CPU1_SB_DQ<23>
  VSS121  = GND
  DQ26_B  = M_E_CPU1_SB_DQ<26>
  VSS122  = GND
  DQ27_B  = M_E_CPU1_SB_DQ<27>
  VSS123  = GND
  \dqs8_b_c||tdqs8_b_c\  = M_E_CPU1_SB_DQS_DN<8>
  \dqs8_b_t||tdqs8_b_t\  = M_E_CPU1_SB_DQS_DP<8>
  VSS124  = GND
  DQ30_B  = M_E_CPU1_SB_DQ<30>
  VSS125  = GND
  DQ31_B  = M_E_CPU1_SB_DQ<31>
  VSS126  = GND
  G1  = GND
  G2  = GND
  G3  = GND

(kicad_pcb
	(version 20260206)
	(generator "pcbnew")
	(generator_version "10.0")
	(general
		(thickness 1.6)
		(legacy_teardrops no)
	)
	(paper "A4")
	(title_block
		(title "04192023_DAF0TMB3IC0_F0TG_MB_C_brd_V02_OCP.brd")
		(comment 1 "Grand Teton / footprint 4612 of 8354 (J32), pads 93-138 of 291")
	)
	(layers
		(0 "F.Cu" signal "TOP")
		(4 "In1.Cu" signal "GND")
		(6 "In2.Cu" signal "IN1")
		(8 "In3.Cu" signal "GND1")
		(10 "In4.Cu" signal "IN2")
		(12 "In5.Cu" signal "GND2")
		(14 "In6.Cu" signal "IN3")
		(16 "In7.Cu" signal "GND3")
		(18 "In8.Cu" signal "VCC")
		(20 "In9.Cu" signal "VCC1")
		(22 "In10.Cu" signal "GND4")
		(24 "In11.Cu" signal "IN4")
		(26 "In12.Cu" signal "GND5")
		(28 "In13.Cu" signal "IN5")
		(30 "In14.Cu" signal "GND6")
		(32 "In15.Cu" signal "IN6")
		(34 "In16.Cu" signal "GND7")
		(2 "B.Cu" signal "BOTTOM")
		(9 "F.Adhes" user "F.Adhesive")
		(11 "B.Adhes" user "B.Adhesive")
		(13 "F.Paste" user "Package Geometry/Pastemask Top")
		(15 "B.Paste" user "Package Geometry/Pastemask Bottom")
		(5 "F.SilkS" user "Ref Des/Silkscreen Top")
		(7 "B.SilkS" user "Ref Des/Silkscreen Bottom")
		(1 "F.Mask" user "Board Geometry/Soldermask Top")
		(3 "B.Mask" user "Board Geometry/Soldermask Bottom")
		(17 "Dwgs.User" user "User.Drawings")
		(19 "Cmts.User" user "User.Comments")
		(21 "Eco1.User" user "User.Eco1")
		(23 "Eco2.User" user "User.Eco2")
		(25 "Edge.Cuts" user "Board Geometry/Outline")
		(27 "Margin" user)
		(31 "F.CrtYd" user "Package Geometry/Place Bound Top")
		(29 "B.CrtYd" user "Package Geometry/Place Bound Bottom")
		(35 "F.Fab" user "Ref Des/Assembly Top")
		(33 "B.Fab" user "Ref Des/Assembly Bottom")
	)
	(footprint ""
		(layer "F.Cu")
		(at 27.20213 -255.560322 180)
		(property "Reference" "J32"
			(at 1.80086 -81.974436 0)
			(unlocked yes)
			(layer "F.SilkS")
			(effects
				(font
					(size 0.7874 0.5842)
					(thickness 0.1524)
				)
			)
		)
		(property "Value" ""
			(at 0 0 180)
			(layer "F.Fab")
			(effects
				(font
					(size 1.27 1.27)
				)
			)
		)
		(duplicate_pad_numbers_are_jumpers no)
		(pad "93" smd rect
			(at -2.050034 19.975068 90)
			(size 0.519938 1.4986)
			(layers "F.Cu" "F.Mask" "F.Paste")
			(net "M_E_CPU1_SB_DQS_DP<9>")
		)
		(pad "94" smd rect
			(at -2.050034 20.824952 90)
			(size 0.519938 1.4986)
			(layers "F.Cu" "F.Mask" "F.Paste")
			(net "M_E_CPU1_SB_DQS_DN<9>")
		)
		(pad "95" smd rect
			(at -2.050034 21.67509 90)
			(size 0.519938 1.4986)
			(layers "F.Cu" "F.Mask" "F.Paste")
			(net "GND")
		)
		(pad "96" smd rect
			(at -2.050034 22.524974 90)
			(size 0.519938 1.4986)
			(layers "F.Cu" "F.Mask" "F.Paste")
			(net "M_E_CPU1_SB_CB<0>")
		)
		(pad "97" smd rect
			(at -2.050034 23.375112 90)
			(size 0.519938 1.4986)
			(layers "F.Cu" "F.Mask" "F.Paste")
			(net "GND")
		)
		(pad "98" smd rect
			(at -2.050034 24.224996 90)
			(size 0.519938 1.4986)
			(layers "F.Cu" "F.Mask" "F.Paste")
			(net "M_E_CPU1_SB_CB<1>")
		)
		(pad "99" smd rect
			(at -2.050034 25.07488 90)
			(size 0.519938 1.4986)
			(layers "F.Cu" "F.Mask" "F.Paste")
			(net "GND")
		)
		(pad "100" smd rect
			(at -2.050034 25.925018 90)
			(size 0.519938 1.4986)
			(layers "F.Cu" "F.Mask" "F.Paste")
			(net "M_E_CPU1_SB_DQ<0>")
		)
		(pad "101" smd rect
			(at -2.050034 26.774902 90)
			(size 0.519938 1.4986)
			(layers "F.Cu" "F.Mask" "F.Paste")
			(net "GND")
		)
		(pad "102" smd rect
			(at -2.050034 27.62504 90)
			(size 0.519938 1.4986)
			(layers "F.Cu" "F.Mask" "F.Paste")
			(net "M_E_CPU1_SB_DQ<1>")
		)
		(pad "103" smd rect
			(at -2.050034 28.474924 90)
			(size 0.519938 1.4986)
			(layers "F.Cu" "F.Mask" "F.Paste")
			(net "GND")
		)
		(pad "104" smd rect
			(at -2.050034 29.325062 90)
			(size 0.519938 1.4986)
			(layers "F.Cu" "F.Mask" "F.Paste")
			(net "M_E_CPU1_SB_DQS_DP<0>")
		)
		(pad "105" smd rect
			(at -2.050034 30.174946 90)
			(size 0.519938 1.4986)
			(layers "F.Cu" "F.Mask" "F.Paste")
			(net "M_E_CPU1_SB_DQS_DN<0>")
		)
		(pad "106" smd rect
			(at -2.050034 31.025084 90)
			(size 0.519938 1.4986)
			(layers "F.Cu" "F.Mask" "F.Paste")
			(net "GND")
		)
		(pad "107" smd rect
			(at -2.050034 31.874968 90)
			(size 0.519938 1.4986)
			(layers "F.Cu" "F.Mask" "F.Paste")
			(net "M_E_CPU1_SB_DQ<4>")
		)
		(pad "108" smd rect
			(at -2.050034 32.725106 90)
			(size 0.519938 1.4986)
			(layers "F.Cu" "F.Mask" "F.Paste")
			(net "GND")
		)
		(pad "109" smd rect
			(at -2.050034 33.57499 90)
			(size 0.519938 1.4986)
			(layers "F.Cu" "F.Mask" "F.Paste")
			(net "M_E_CPU1_SB_DQ<5>")
		)
		(pad "110" smd rect
			(at -2.050034 34.425128 90)
			(size 0.519938 1.4986)
			(layers "F.Cu" "F.Mask" "F.Paste")
			(net "GND")
		)
		(pad "111" smd rect
			(at -2.050034 35.275012 90)
			(size 0.519938 1.4986)
			(layers "F.Cu" "F.Mask" "F.Paste")
			(net "M_E_CPU1_SB_DQ<8>")
		)
		(pad "112" smd rect
			(at -2.050034 36.124896 90)
			(size 0.519938 1.4986)
			(layers "F.Cu" "F.Mask" "F.Paste")
			(net "GND")
		)
		(pad "113" smd rect
			(at -2.050034 36.975034 90)
			(size 0.519938 1.4986)
			(layers "F.Cu" "F.Mask" "F.Paste")
			(net "M_E_CPU1_SB_DQ<9>")
		)
		(pad "114" smd rect
			(at -2.050034 37.824918 90)
			(size 0.519938 1.4986)
			(layers "F.Cu" "F.Mask" "F.Paste")
			(net "GND")
		)
		(pad "115" smd rect
			(at -2.050034 38.675056 90)
			(size 0.519938 1.4986)
			(layers "F.Cu" "F.Mask" "F.Paste")
			(net "M_E_CPU1_SB_DQS_DP<1>")
		)
		(pad "116" smd rect
			(at -2.050034 39.52494 90)
			(size 0.519938 1.4986)
			(layers "F.Cu" "F.Mask" "F.Paste")
			(net "M_E_CPU1_SB_DQS_DN<1>")
		)
		(pad "117" smd rect
			(at -2.050034 40.375078 90)
			(size 0.519938 1.4986)
			(layers "F.Cu" "F.Mask" "F.Paste")
			(net "GND")
		)
		(pad "118" smd rect
			(at -2.050034 41.224962 90)
			(size 0.519938 1.4986)
			(layers "F.Cu" "F.Mask" "F.Paste")
			(net "M_E_CPU1_SB_DQ<12>")
		)
		(pad "119" smd rect
			(at -2.050034 42.0751 90)
			(size 0.519938 1.4986)
			(layers "F.Cu" "F.Mask" "F.Paste")
			(net "GND")
		)
		(pad "120" smd rect
			(at -2.050034 42.924984 90)
			(size 0.519938 1.4986)
			(layers "F.Cu" "F.Mask" "F.Paste")
			(net "M_E_CPU1_SB_DQ<13>")
		)
		(pad "121" smd rect
			(at -2.050034 43.775122 90)
			(size 0.519938 1.4986)
			(layers "F.Cu" "F.Mask" "F.Paste")
			(net "GND")
		)
		(pad "122" smd rect
			(at -2.050034 44.625006 90)
			(size 0.519938 1.4986)
			(layers "F.Cu" "F.Mask" "F.Paste")
			(net "M_E_CPU1_SB_DQ<16>")
		)
		(pad "123" smd rect
			(at -2.050034 45.47489 90)
			(size 0.519938 1.4986)
			(layers "F.Cu" "F.Mask" "F.Paste")
			(net "GND")
		)
		(pad "124" smd rect
			(at -2.050034 46.325028 90)
			(size 0.519938 1.4986)
			(layers "F.Cu" "F.Mask" "F.Paste")
			(net "M_E_CPU1_SB_DQ<17>")
		)
		(pad "125" smd rect
			(at -2.050034 47.174912 90)
			(size 0.519938 1.4986)
			(layers "F.Cu" "F.Mask" "F.Paste")
			(net "GND")
		)
		(pad "126" smd rect
			(at -2.050034 48.02505 90)
			(size 0.519938 1.4986)
			(layers "F.Cu" "F.Mask" "F.Paste")
			(net "M_E_CPU1_SB_DQS_DP<2>")
		)
		(pad "127" smd rect
			(at -2.050034 48.874934 90)
			(size 0.519938 1.4986)
			(layers "F.Cu" "F.Mask" "F.Paste")
			(net "M_E_CPU1_SB_DQS_DN<2>")
		)
		(pad "128" smd rect
			(at -2.050034 49.725072 90)
			(size 0.519938 1.4986)
			(layers "F.Cu" "F.Mask" "F.Paste")
			(net "GND")
		)
		(pad "129" smd rect
			(at -2.050034 50.574956 90)
			(size 0.519938 1.4986)
			(layers "F.Cu" "F.Mask" "F.Paste")
			(net "M_E_CPU1_SB_DQ<20>")
		)
		(pad "130" smd rect
			(at -2.050034 51.425094 90)
			(size 0.519938 1.4986)
			(layers "F.Cu" "F.Mask" "F.Paste")
			(net "GND")
		)
		(pad "131" smd rect
			(at -2.050034 52.274978 90)
			(size 0.519938 1.4986)
			(layers "F.Cu" "F.Mask" "F.Paste")
			(net "M_E_CPU1_SB_DQ<21>")
		)
		(pad "132" smd rect
			(at -2.050034 53.125116 90)
			(size 0.519938 1.4986)
			(layers "F.Cu" "F.Mask" "F.Paste")
			(net "GND")
		)
		(pad "133" smd rect
			(at -2.050034 53.975 90)
			(size 0.519938 1.4986)
			(layers "F.Cu" "F.Mask" "F.Paste")
			(net "M_E_CPU1_SB_DQ<24>")
		)
		(pad "134" smd rect
			(at -2.050034 54.824884 90)
			(size 0.519938 1.4986)
			(layers "F.Cu" "F.Mask" "F.Paste")
			(net "GND")
		)
		(pad "135" smd rect
			(at -2.050034 55.675022 90)
			(size 0.519938 1.4986)
			(layers "F.Cu" "F.Mask" "F.Paste")
			(net "M_E_CPU1_SB_DQ<25>")
		)
		(pad "136" smd rect
			(at -2.050034 56.524906 90)
			(size 0.519938 1.4986)
			(layers "F.Cu" "F.Mask" "F.Paste")
			(net "GND")
		)
		(pad "137" smd rect
			(at -2.050034 57.375044 90)
			(size 0.519938 1.4986)
			(layers "F.Cu" "F.Mask" "F.Paste")
			(net "M_E_CPU1_SB_DQS_DP<3>")
		)
		(pad "138" smd rect
			(at -2.050034 58.224928 90)
			(size 0.519938 1.4986)
			(layers "F.Cu" "F.Mask" "F.Paste")
			(net "M_E_CPU1_SB_DQS_DN<3>")
		)
	)
)
